# T6G (Grand Teton) — schematic parts with pin connectivity, parts 1718–1902 of 8303; source: Cadence DE-HDL packaged netlist (pstxprt.dat, pstxnet.dat, pstchip.dat)

C2469  Q_CAP  22UF 4V 20% X6S  pkg C0402  page 74 : 1 = PVDDCR_SOC_P1 ; 2 = GND
C2470  Q_CAP  22UF 4V 20% X6S  pkg C0402  page 74 : 1 = PVDDCR_SOC_P1 ; 2 = GND
C2471  Q_CAP  22UF 4V 20% X6S  pkg C0402  page 74 : 1 = PVDDCR_SOC_P1 ; 2 = GND
C2472  Q_CAP  22UF 4V 20% X6S  pkg C0402  page 74 : 1 = PVDDCR_SOC_P1 ; 2 = GND
C2473  Q_CAP  22UF 4V 20% X6S  pkg C0402  page 74 : 1 = PVDDCR_SOC_P1 ; 2 = GND
C2474  Q_CAP  22UF 4V 20% X6S  pkg C0402  page 74 : 1 = PVDDCR_SOC_P1 ; 2 = GND
C2475  Q_CAP  22UF 4V 20% X6S  pkg C0402  page 74 : 1 = PVDDCR_SOC_P1 ; 2 = GND
C2476  Q_CAP  22UF 4V 20% X6S  pkg C0402  page 74 : 1 = PVDDCR_SOC_P1 ; 2 = GND
C2477  Q_CAP  22UF 4V 20% X6S  pkg C0402  page 74 : 1 = PVDDIO_P1 ; 2 = GND
C2478  Q_CAP  22UF 4V 20% X6S  pkg C0402  page 74 : 1 = PVDDIO_P1 ; 2 = GND
C2479  Q_CAP  22UF 4V 20% X6S  pkg C0402  page 74 : 1 = PVDDIO_P1 ; 2 = GND
C2480  Q_CAP  22UF 4V 20% X6S  pkg C0402  page 74 : 1 = PVDD11_S3_P1 ; 2 = GND
C2481  Q_CAP  22UF 4V 20% X6S  pkg C0402  page 74 : 1 = PVDD11_S3_P1 ; 2 = GND
C2482  Q_CAP  22UF 4V 20% X6S  pkg C0402  page 74 : 1 = PVDD11_S3_P1 ; 2 = GND
C2483  Q_CAP  22UF 4V 20% X6S  pkg C0402  page 74 : 1 = PVDD11_S3_P1 ; 2 = GND
C2484  Q_CAP  22UF 4V 20% X6S  pkg C0402  page 74 : 1 = PVDDIO_P1 ; 2 = GND
C2485  Q_CAP  22UF 4V 20% X6S  pkg C0402  page 74 : 1 = PVDD11_S3_P1 ; 2 = GND
C2486  Q_CAP  22UF 4V 20% X6S  pkg C0402  page 74 : 1 = PVDD11_S3_P1 ; 2 = GND
C2487  Q_CAP  22UF 4V 20% X6S  pkg C0402  page 74 : 1 = PVDD11_S3_P1 ; 2 = GND
C2488  Q_CAP  22UF 4V 20% X6S  pkg C0402  page 74 : 1 = PVDD11_S3_P1 ; 2 = GND
C2489  Q_CAP  22UF 4V 20% X6S  pkg C0402  page 74 : 1 = PVDD11_S3_P1 ; 2 = GND
C2490  Q_CAP  22UF 4V 20% X6S  pkg C0402  page 74 : 1 = PVDD11_S3_P1 ; 2 = GND
C2491  Q_CAP  22UF 4V 20% X6S  pkg C0402  page 74 : 1 = PVDD11_S3_P1 ; 2 = GND
C2492  Q_CAP  22UF 4V 20% X6S  pkg C0402  page 74 : 1 = PVDD11_S3_P1 ; 2 = GND
C2493  Q_CAP  22UF 4V 20% X6S  pkg C0402  page 74 : 1 = PVDDIO_P1 ; 2 = GND
C2494  Q_CAP  22UF 4V 20% X6S  pkg C0402  page 74 : 1 = PVDD11_S3_P1 ; 2 = GND
C2495  Q_CAP  22UF 4V 20% X6S  pkg C0402  page 74 : 1 = PVDD11_S3_P1 ; 2 = GND
C2496  Q_CAP  22UF 4V 20% X6S  pkg C0402  page 74 : 1 = PVDD11_S3_P1 ; 2 = GND
C2497  Q_CAP  22UF 4V 20% X6S  pkg C0402  page 74 : 1 = PVDD11_S3_P1 ; 2 = GND
C2498  Q_CAP  22UF 4V 20% X6S  pkg C0402  page 74 : 1 = PVDDIO_P1 ; 2 = GND
C2499  Q_CAP  22UF 4V 20% X6S  pkg C0402  page 74 : 1 = PVDD11_S3_P1 ; 2 = GND
C2500  Q_CAP  22UF 4V 20% X6S  pkg C0402  page 74 : 1 = PVDD11_S3_P1 ; 2 = GND
C2501  Q_CAP  22UF 4V 20% X6S  pkg C0402  page 74 : 1 = PVDD11_S3_P1 ; 2 = GND
C2502  Q_CAP  22UF 4V 20% X6S  pkg C0402  page 74 : 1 = PVDD11_S3_P1 ; 2 = GND
C2503  Q_CAP  22UF 4V 20% X6S  pkg C0402  page 74 : 1 = PVDD11_S3_P1 ; 2 = GND
C2504  Q_CAP  22UF 4V 20% X6S  pkg C0402  page 74 : 1 = PVDD11_S3_P1 ; 2 = GND
C2505  Q_CAP  22UF 4V 20% X6S  pkg C0402  page 74 : 1 = PVDD11_S3_P1 ; 2 = GND
C2506  Q_CAP  22UF 4V 20% X6S  pkg C0402  page 74 : 1 = PVDD11_S3_P1 ; 2 = GND
C2507  Q_CAP  22UF 4V 20% X6S  pkg C0402  page 74 : 1 = PVDDIO_P1 ; 2 = GND
C2508  Q_CAP  22UF 4V 20% X6S  pkg C0402  page 74 : 1 = PVDD11_S3_P1 ; 2 = GND
C2509  Q_CAP  22UF 4V 20% X6S  pkg C0402  page 74 : 1 = PVDDIO_P1 ; 2 = GND
C2510  Q_CAP  22UF 4V 20% X6S  pkg C0402  page 74 : 1 = PVDD11_S3_P1 ; 2 = GND
C2511  Q_CAP  22UF 4V 20% X6S  pkg C0402  page 74 : 1 = PVDD11_S3_P1 ; 2 = GND
C2512  Q_CAP  10UF 6.3V 20% X6S  pkg C0402  page 71 : 1 = PVDD_33_S5 ; 2 = GND
C2513  Q_CAP  22UF 4V 20% X6S  pkg C0402  page 71 : 1 = PVDD18_S5_P0 ; 2 = GND
C2514  Q_CAP  22UF 4V 20% X6S  pkg C0402  page 71 : 1 = PVDD18_S5_P0 ; 2 = GND
C2515  Q_CAP  10UF 6.3V 20% X6S  pkg C0402  page 71 : 1 = PVDD_33_S5 ; 2 = GND
C2516  Q_CAP  22UF 4V 20% X6S  pkg C0402  page 71 : 1 = PVDD18_S5_P0 ; 2 = GND
C2517  Q_CAP  22UF 4V 20% X6S  pkg C0402  page 71 : 1 = PVDD18_S5_P0 ; 2 = GND
C2518  Q_CAP  22UF 4V 20% X6S  pkg C0402  page 71 : 1 = PVDD18_S5_P0 ; 2 = GND
C2520  Q_CAP  22UF 4V 20% X6S  pkg C0402  page 71 : 1 = PVDD18_S5_P0 ; 2 = GND
C2521  Q_CAP  22UF 4V 20% X6S  pkg C0402  page 71 : 1 = PVDD18_S5_P0 ; 2 = GND
C2522  Q_CAP  22UF 4V 20% X6S  pkg C0402  page 71 : 1 = PVDD18_S5_P0 ; 2 = GND
C2523  Q_CAP  22UF 4V 20% X6S  pkg C0402  page 71 : 1 = PVDD18_S5_P0 ; 2 = GND
C2524  Q_CAP  22UF 4V 20% X6S  pkg C0402  page 71 : 1 = PVDD18_S5_P0 ; 2 = GND
C2525  Q_CAP  22UF 4V 20% X6S  pkg C0402  page 71 : 1 = PVDD18_S5_P0 ; 2 = GND
C2526  Q_CAP  22UF 4V 20% X6S  pkg C0402  page 71 : 1 = PVDD18_S5_P0 ; 2 = GND
C2527  Q_CAP  22UF 4V 20% X6S  pkg C0402  page 70 : 1 = PVDDCR_SOC_P0 ; 2 = GND
C2528  Q_CAP  22UF 4V 20% X6S  pkg C0402  page 70 : 1 = PVDDCR_SOC_P0 ; 2 = GND
C2529  Q_CAP  22UF 4V 20% X6S  pkg C0402  page 70 : 1 = PVDDCR_SOC_P0 ; 2 = GND
C2530  Q_CAP  22UF 4V 20% X6S  pkg C0402  page 70 : 1 = PVDDCR_SOC_P0 ; 2 = GND
C2531  Q_CAP  22UF 4V 20% X6S  pkg C0402  page 70 : 1 = PVDDCR_SOC_P0 ; 2 = GND
C2532  Q_CAP  22UF 4V 20% X6S  pkg C0402  page 70 : 1 = PVDDCR_SOC_P0 ; 2 = GND
C2533  Q_CAP  22UF 4V 20% X6S  pkg C0402  page 70 : 1 = PVDDCR_SOC_P0 ; 2 = GND
C2534  Q_CAP  22UF 4V 20% X6S  pkg C0402  page 70 : 1 = PVDDCR_SOC_P0 ; 2 = GND
C2535  Q_CAP  22UF 4V 20% X6S  pkg C0402  page 70 : 1 = PVDDCR_SOC_P0 ; 2 = GND
C2536  Q_CAP  22UF 4V 20% X6S  pkg C0402  page 70 : 1 = PVDDCR_SOC_P0 ; 2 = GND
C2537  Q_CAP  22UF 4V 20% X6S  pkg C0402  page 70 : 1 = PVDDCR_SOC_P0 ; 2 = GND
C2538  Q_CAP  22UF 4V 20% X6S  pkg C0402  page 70 : 1 = PVDDCR_SOC_P0 ; 2 = GND
C2539  Q_CAP  22UF 4V 20% X6S  pkg C0402  page 70 : 1 = PVDDCR_SOC_P0 ; 2 = GND
C2540  Q_CAP  22UF 4V 20% X6S  pkg C0402  page 70 : 1 = PVDDCR_SOC_P0 ; 2 = GND
C2541  Q_CAP  22UF 4V 20% X6S  pkg C0402  page 70 : 1 = PVDDCR_SOC_P0 ; 2 = GND
C2542  Q_CAP  22UF 4V 20% X6S  pkg C0402  page 70 : 1 = PVDDCR_SOC_P0 ; 2 = GND
C2543  Q_CAP  22UF 4V 20% X6S  pkg C0402  page 70 : 1 = PVDDCR_SOC_P0 ; 2 = GND
C2544  Q_CAP  22UF 4V 20% X6S  pkg C0402  page 70 : 1 = PVDDCR_SOC_P0 ; 2 = GND
C2545  Q_CAP  22UF 4V 20% X6S  pkg C0402  page 70 : 1 = PVDDCR_SOC_P0 ; 2 = GND
C2546  Q_CAP  22UF 4V 20% X6S  pkg C0402  page 70 : 1 = PVDDCR_SOC_P0 ; 2 = GND
C2547  Q_CAP  22UF 4V 20% X6S  pkg C0402  page 70 : 1 = PVDDCR_SOC_P0 ; 2 = GND
C2548  Q_CAP  22UF 4V 20% X6S  pkg C0402  page 70 : 1 = PVDDCR_SOC_P0 ; 2 = GND
C2549  Q_CAP  22UF 4V 20% X6S  pkg C0402  page 70 : 1 = PVDDCR_SOC_P0 ; 2 = GND
C2550  Q_CAP  22UF 4V 20% X6S  pkg C0402  page 70 : 1 = PVDDCR_SOC_P0 ; 2 = GND
C2551  Q_CAP  22UF 4V 20% X6S  pkg C0402  page 70 : 1 = PVDDCR_SOC_P0 ; 2 = GND
C2552  Q_CAP  22UF 4V 20% X6S  pkg C0402  page 70 : 1 = PVDDCR_SOC_P0 ; 2 = GND
C2553  Q_CAP  22UF 4V 20% X6S  pkg C0402  page 70 : 1 = PVDDCR_SOC_P0 ; 2 = GND
C2554  Q_CAP  22UF 4V 20% X6S  pkg C0402  page 70 : 1 = PVDDCR_SOC_P0 ; 2 = GND
C2555  Q_CAP  22UF 4V 20% X6S  pkg C0402  page 70 : 1 = PVDDCR_SOC_P0 ; 2 = GND
C2556  Q_CAP  22UF 4V 20% X6S  pkg C0402  page 70 : 1 = PVDDCR_SOC_P0 ; 2 = GND
C2557  Q_CAP  22UF 4V 20% X6S  pkg C0402  page 70 : 1 = PVDDCR_SOC_P0 ; 2 = GND
C2558  Q_CAP  22UF 4V 20% X6S  pkg C0402  page 70 : 1 = PVDDCR_SOC_P0 ; 2 = GND
C2559  Q_CAP  22UF 4V 20% X6S  pkg C0402  page 70 : 1 = PVDDCR_SOC_P0 ; 2 = GND
C2560  Q_CAP  22UF 4V 20% X6S  pkg C0402  page 70 : 1 = PVDDCR_SOC_P0 ; 2 = GND
C2561  Q_CAP  22UF 4V 20% X6S  pkg C0402  page 70 : 1 = PVDDCR_SOC_P0 ; 2 = GND
C2562  Q_CAP  22UF 4V 20% X6S  pkg C0402  page 70 : 1 = PVDDCR_SOC_P0 ; 2 = GND
C2563  Q_CAP  22UF 4V 20% X6S  pkg C0402  page 70 : 1 = PVDDCR_SOC_P0 ; 2 = GND
C2564  Q_CAP  22UF 4V 20% X6S  pkg C0402  page 70 : 1 = PVDDCR_SOC_P0 ; 2 = GND
C2565  Q_CAP  22UF 4V 20% X6S  pkg C0402  page 70 : 1 = PVDDCR_SOC_P0 ; 2 = GND
C2566  Q_CAP  22UF 4V 20% X6S  pkg C0402  page 70 : 1 = PVDDCR_SOC_P0 ; 2 = GND
C2567  Q_CAP  22UF 4V 20% X6S  pkg C0402  page 70 : 1 = PVDDCR_SOC_P0 ; 2 = GND
C2568  Q_CAP  22UF 4V 20% X6S  pkg C0402  page 70 : 1 = PVDDCR_SOC_P0 ; 2 = GND
C2569  Q_CAP  22UF 4V 20% X6S  pkg C0402  page 70 : 1 = PVDDCR_SOC_P0 ; 2 = GND
C2570  Q_CAP  22UF 4V 20% X6S  pkg C0402  page 70 : 1 = PVDDCR_SOC_P0 ; 2 = GND
C2571  Q_CAP  22UF 4V 20% X6S  pkg C0402  page 70 : 1 = PVDDCR_SOC_P0 ; 2 = GND
C2572  Q_CAP  22UF 4V 20% X6S  pkg C0402  page 70 : 1 = PVDDCR_SOC_P0 ; 2 = GND
C2573  Q_CAP  22UF 4V 20% X6S  pkg C0402  page 70 : 1 = PVDDCR_SOC_P0 ; 2 = GND
C2574  Q_CAP  22UF 4V 20% X6S  pkg C0402  page 70 : 1 = PVDDCR_SOC_P0 ; 2 = GND
C2575  Q_CAP  22UF 4V 20% X6S  pkg C0402  page 70 : 1 = PVDDCR_SOC_P0 ; 2 = GND
C2576  Q_CAP  22UF 4V 20% X6S  pkg C0402  page 70 : 1 = PVDDCR_SOC_P0 ; 2 = GND
C2577  Q_CAP  22UF 4V 20% X6S  pkg C0402  page 70 : 1 = PVDDCR_SOC_P0 ; 2 = GND
C2578  Q_CAP  22UF 4V 20% X6S  pkg C0402  page 70 : 1 = PVDDCR_SOC_P0 ; 2 = GND
C2579  Q_CAP  22UF 4V 20% X6S  pkg C0402  page 70 : 1 = PVDDCR_SOC_P0 ; 2 = GND
C2580  Q_CAP  22UF 4V 20% X6S  pkg C0402  page 70 : 1 = PVDDCR_SOC_P0 ; 2 = GND
C2581  Q_CAP  22UF 4V 20% X6S  pkg C0402  page 70 : 1 = PVDDCR_SOC_P0 ; 2 = GND
C2582  Q_CAP  22UF 4V 20% X6S  pkg C0402  page 70 : 1 = PVDDCR_SOC_P0 ; 2 = GND
C2583  Q_CAP  22UF 4V 20% X6S  pkg C0402  page 70 : 1 = PVDDCR_SOC_P0 ; 2 = GND
C2584  Q_CAP  22UF 4V 20% X6S  pkg C0402  page 70 : 1 = PVDDCR_SOC_P0 ; 2 = GND
C2585  Q_CAP  22UF 4V 20% X6S  pkg C0402  page 70 : 1 = PVDDCR_SOC_P0 ; 2 = GND
C2586  Q_CAP  22UF 4V 20% X6S  pkg C0402  page 70 : 1 = PVDDCR_SOC_P0 ; 2 = GND
C2587  Q_CAP  22UF 4V 20% X6S  pkg C0402  page 70 : 1 = PVDDCR_SOC_P0 ; 2 = GND
C2588  Q_CAP  22UF 4V 20% X6S  pkg C0402  page 70 : 1 = PVDDCR_SOC_P0 ; 2 = GND
C2589  Q_CAP  22UF 4V 20% X6S  pkg C0402  page 70 : 1 = PVDDCR_SOC_P0 ; 2 = GND
C2590  Q_CAP  22UF 4V 20% X6S  pkg C0402  page 70 : 1 = PVDDCR_SOC_P0 ; 2 = GND
C2591  Q_CAP  22UF 4V 20% X6S  pkg C0402  page 70 : 1 = PVDDCR_SOC_P0 ; 2 = GND
C2592  Q_CAP  22UF 4V 20% X6S  pkg C0402  page 70 : 1 = PVDDCR_SOC_P0 ; 2 = GND
C2593  Q_CAP  22UF 4V 20% X6S  pkg C0402  page 70 : 1 = PVDDCR_SOC_P0 ; 2 = GND
C2594  Q_CAP  22UF 4V 20% X6S  pkg C0402  page 70 : 1 = PVDDCR_SOC_P0 ; 2 = GND
C2595  Q_CAP  22UF 4V 20% X6S  pkg C0402  page 70 : 1 = PVDDCR_SOC_P0 ; 2 = GND
C2596  Q_CAP  22UF 4V 20% X6S  pkg C0402  page 70 : 1 = PVDDCR_SOC_P0 ; 2 = GND
C2597  Q_CAP  22UF 4V 20% X6S  pkg C0402  page 70 : 1 = PVDDIO_P0 ; 2 = GND
C2598  Q_CAP  22UF 4V 20% X6S  pkg C0402  page 70 : 1 = PVDDIO_P0 ; 2 = GND
C2599  Q_CAP  22UF 4V 20% X6S  pkg C0402  page 70 : 1 = PVDDIO_P0 ; 2 = GND
C2600  Q_CAP  22UF 4V 20% X6S  pkg C0402  page 70 : 1 = PVDD11_S3_P0 ; 2 = GND
C2601  Q_CAP  22UF 4V 20% X6S  pkg C0402  page 70 : 1 = PVDD11_S3_P0 ; 2 = GND
C2602  Q_CAP  22UF 4V 20% X6S  pkg C0402  page 70 : 1 = PVDD11_S3_P0 ; 2 = GND
C2603  Q_CAP  22UF 4V 20% X6S  pkg C0402  page 70 : 1 = PVDD11_S3_P0 ; 2 = GND
C2604  Q_CAP  22UF 4V 20% X6S  pkg C0402  page 70 : 1 = PVDDIO_P0 ; 2 = GND
C2605  Q_CAP  22UF 4V 20% X6S  pkg C0402  page 70 : 1 = PVDDIO_P0 ; 2 = GND
C2606  Q_CAP  22UF 4V 20% X6S  pkg C0402  page 70 : 1 = PVDDIO_P0 ; 2 = GND
C2607  Q_CAP  22UF 4V 20% X6S  pkg C0402  page 70 : 1 = PVDD11_S3_P0 ; 2 = GND
C2608  Q_CAP  22UF 4V 20% X6S  pkg C0402  page 70 : 1 = PVDD11_S3_P0 ; 2 = GND
C2609  Q_CAP  22UF 4V 20% X6S  pkg C0402  page 70 : 1 = PVDD11_S3_P0 ; 2 = GND
C2610  Q_CAP  22UF 4V 20% X6S  pkg C0402  page 70 : 1 = PVDD11_S3_P0 ; 2 = GND
C2611  Q_CAP  22UF 4V 20% X6S  pkg C0402  page 70 : 1 = PVDDIO_P0 ; 2 = GND
C2612  Q_CAP  22UF 4V 20% X6S  pkg C0402  page 70 : 1 = PVDDIO_P0 ; 2 = GND
C2613  Q_CAP  22UF 4V 20% X6S  pkg C0402  page 70 : 1 = PVDDIO_P0 ; 2 = GND
C2614  Q_CAP  22UF 4V 20% X6S  pkg C0402  page 70 : 1 = PVDD11_S3_P0 ; 2 = GND
C2615  Q_CAP  22UF 4V 20% X6S  pkg C0402  page 70 : 1 = PVDD11_S3_P0 ; 2 = GND
C2616  Q_CAP  22UF 4V 20% X6S  pkg C0402  page 70 : 1 = PVDD11_S3_P0 ; 2 = GND
C2617  Q_CAP  22UF 4V 20% X6S  pkg C0402  page 70 : 1 = PVDD11_S3_P0 ; 2 = GND
C2618  Q_CAP  22UF 4V 20% X6S  pkg C0402  page 70 : 1 = PVDDIO_P0 ; 2 = GND
C2619  Q_CAP  22UF 4V 20% X6S  pkg C0402  page 70 : 1 = PVDDIO_P0 ; 2 = GND
C2620  Q_CAP  22UF 4V 20% X6S  pkg C0402  page 70 : 1 = PVDDIO_P0 ; 2 = GND
C2621  Q_CAP  22UF 4V 20% X6S  pkg C0402  page 70 : 1 = PVDD11_S3_P0 ; 2 = GND
C2622  Q_CAP  22UF 4V 20% X6S  pkg C0402  page 70 : 1 = PVDD11_S3_P0 ; 2 = GND
C2623  Q_CAP  22UF 4V 20% X6S  pkg C0402  page 70 : 1 = PVDD11_S3_P0 ; 2 = GND
C2624  Q_CAP  22UF 4V 20% X6S  pkg C0402  page 70 : 1 = PVDD11_S3_P0 ; 2 = GND
C2625  Q_CAP  22UF 4V 20% X6S  pkg C0402  page 70 : 1 = PVDDIO_P0 ; 2 = GND
C2626  Q_CAP  22UF 4V 20% X6S  pkg C0402  page 70 : 1 = PVDDIO_P0 ; 2 = GND
C2627  Q_CAP  22UF 4V 20% X6S  pkg C0402  page 70 : 1 = PVDD11_S3_P0 ; 2 = GND
C2628  Q_CAP  22UF 4V 20% X6S  pkg C0402  page 70 : 1 = PVDD11_S3_P0 ; 2 = GND
C2629  Q_CAP  22UF 4V 20% X6S  pkg C0402  page 70 : 1 = PVDD11_S3_P0 ; 2 = GND
C2630  Q_CAP  22UF 4V 20% X6S  pkg C0402  page 70 : 1 = PVDD11_S3_P0 ; 2 = GND
C2631  Q_CAP  22UF 4V 20% X6S  pkg C0402  page 70 : 1 = PVDDIO_P0 ; 2 = GND
C2632  Q_CAP  22UF 4V 20% X6S  pkg C0402  page 70 : 1 = PVDDIO_P0 ; 2 = GND
C2633  Q_CAP  22UF 4V 20% X6S  pkg C0402  page 70 : 1 = PVDD11_S3_P0 ; 2 = GND
C2634  Q_CAP  22UF 4V 20% X6S  pkg C0402  page 70 : 1 = PVDD11_S3_P0 ; 2 = GND
C2635  Q_CAP  22UF 4V 20% X6S  pkg C0402  page 70 : 1 = PVDD11_S3_P0 ; 2 = GND
C2636  Q_CAP  22UF 4V 20% X6S  pkg C0402  page 70 : 1 = PVDD11_S3_P0 ; 2 = GND
C2637  Q_CAP  22UF 4V 20% X6S  pkg C0402  page 70 : 1 = PVDDIO_P0 ; 2 = GND
C2638  Q_CAP  22UF 4V 20% X6S  pkg C0402  page 70 : 1 = PVDDIO_P0 ; 2 = GND
C2639  Q_CAP  22UF 4V 20% X6S  pkg C0402  page 70 : 1 = PVDD11_S3_P0 ; 2 = GND
C2640  Q_CAP  22UF 4V 20% X6S  pkg C0402  page 70 : 1 = PVDD11_S3_P0 ; 2 = GND
C2641  Q_CAP  22UF 4V 20% X6S  pkg C0402  page 70 : 1 = PVDD11_S3_P0 ; 2 = GND
C2642  Q_CAP  22UF 4V 20% X6S  pkg C0402  page 70 : 1 = PVDD11_S3_P0 ; 2 = GND
C2643  Q_CAP  22UF 4V 20% X6S  pkg C0402  page 70 : 1 = PVDDIO_P0 ; 2 = GND
C2644  Q_CAP  22UF 4V 20% X6S  pkg C0402  page 70 : 1 = PVDDIO_P0 ; 2 = GND
C2645  Q_CAP  22UF 4V 20% X6S  pkg C0402  page 70 : 1 = PVDD11_S3_P0 ; 2 = GND
C2646  Q_CAP  22UF 4V 20% X6S  pkg C0402  page 70 : 1 = PVDD11_S3_P0 ; 2 = GND
C2647  Q_CAP  22UF 4V 20% X6S  pkg C0402  page 70 : 1 = PVDD11_S3_P0 ; 2 = GND
C2648  Q_CAP  22UF 4V 20% X6S  pkg C0402  page 70 : 1 = PVDD11_S3_P0 ; 2 = GND
C2649  Q_CAP  22UF 4V 20% X6S  pkg C0402  page 70 : 1 = PVDDIO_P0 ; 2 = GND
C2650  Q_CAP  22UF 4V 20% X6S  pkg C0402  page 70 : 1 = PVDDIO_P0 ; 2 = GND
C2651  Q_CAP  22UF 4V 20% X6S  pkg C0402  page 70 : 1 = PVDD11_S3_P0 ; 2 = GND
C2652  Q_CAP  22UF 4V 20% X6S  pkg C0402  page 70 : 1 = PVDD11_S3_P0 ; 2 = GND
C2653  Q_CAP  22UF 4V 20% X6S  pkg C0402  page 70 : 1 = PVDD11_S3_P0 ; 2 = GND
C2654  Q_CAP  22UF 4V 20% X6S  pkg C0402  page 70 : 1 = PVDDIO_P0 ; 2 = GND
